(kicad_pcb
	(version 20260206)
	(generator "pcbnew")
	(generator_version "10.0")
	(general
		(thickness 1.6)
		(legacy_teardrops no)
	)
	(paper "A4")
	(title_block
		(title "pdpb — Lightning_PDPB_BRD.brd")
		(comment 1 "Lightning (Wiwynn / Facebook NVMe JBOF) / footprints 191-196 of 1140")
	)
	(layers
		(0 "F.Cu" signal "TOP")
		(4 "In1.Cu" signal "L2GND")
		(6 "In2.Cu" signal "L3")
		(8 "In3.Cu" signal "L4VCC")
		(10 "In4.Cu" signal "L5VCC")
		(12 "In5.Cu" signal "L6")
		(14 "In6.Cu" signal "L7GND")
		(2 "B.Cu" signal "BOTTOM")
		(9 "F.Adhes" user "F.Adhesive")
		(11 "B.Adhes" user "B.Adhesive")
		(13 "F.Paste" user "Package Geometry/Pastemask Top")
		(15 "B.Paste" user "Package Geometry/Pastemask Bottom")
		(5 "F.SilkS" user "Ref Des/Silkscreen Top")
		(7 "B.SilkS" user "Ref Des/Silkscreen Bottom")
		(1 "F.Mask" user "Board Geometry/Soldermask Top")
		(3 "B.Mask" user "Board Geometry/Soldermask Bottom")
		(17 "Dwgs.User" user "User.Drawings")
		(19 "Cmts.User" user "User.Comments")
		(21 "Eco1.User" user "User.Eco1")
		(23 "Eco2.User" user "User.Eco2")
		(25 "Edge.Cuts" user "Board Geometry/Outline")
		(27 "Margin" user)
		(31 "F.CrtYd" user "Package Geometry/Place Bound Top")
		(29 "B.CrtYd" user "Package Geometry/Place Bound Bottom")
		(35 "F.Fab" user "Ref Des/Assembly Top")
		(33 "B.Fab" user "Ref Des/Assembly Bottom")
	)
	(footprint ""
		(layer "F.Cu")
		(at 208.407 -44.704)
		(property "Reference" "R338"
			(at 0 0 0)
			(layer "F.SilkS")
			(hide yes)
			(effects
				(font
					(size 1.27 1.27)
				)
			)
		)
		(property "Value" "4K7R2J-2-GP"
			(at 0.064008 -3.993896 0)
			(unlocked yes)
			(layer "F.Fab")
			(hide yes)
			(effects
				(font
					(size 1.016 1.016)
					(thickness 0.1524)
				)
			)
		)
		(property "Device Type" "R402H16"
			(at 0.064008 -5.517896 0)
			(unlocked yes)
			(layer "F.Fab")
			(hide yes)
			(effects
				(font
					(size 1.016 1.016)
					(thickness 0.1524)
				)
			)
		)
		(duplicate_pad_numbers_are_jumpers no)
		(fp_line
			(start -0.508 -0.9398)
			(end -0.508 0.9398)
			(stroke
				(width 0.1524)
				(type default)
			)
			(layer "F.SilkS")
		)
		(fp_line
			(start 0.508 -0.9398)
			(end -0.508 -0.9398)
			(stroke
				(width 0.1524)
				(type default)
			)
			(layer "F.SilkS")
		)
		(fp_rect
			(start -0.508 0.9398)
			(end 0.508 -0.9398)
			(stroke
				(width 0)
				(type default)
			)
			(fill no)
			(layer "F.CrtYd")
		)
		(fp_rect
			(start -0.508 0.9398)
			(end 0.508 -0.9398)
			(stroke
				(width 0)
				(type default)
			)
			(fill no)
			(layer "F.Fab")
		)
		(pad "1" smd custom
			(at 0 -0.4445)
			(size 0.1397 0.1397)
			(layers "F.Cu" "F.Mask" "F.Paste")
			(net "I2C_B_TMP3_A0")
			(options
				(clearance outline)
				(anchor circle)
			)
			(primitives
				(gr_poly
					(pts
						(arc
							(start -0.1778 -0.2794)
							(mid -0.249642 -0.249642)
							(end -0.2794 -0.1778)
						)
						(arc
							(start -0.2794 0.1778)
							(mid -0.249642 0.249642)
							(end -0.1778 0.2794)
						)
						(arc
							(start 0.1778 0.2794)
							(mid 0.249642 0.249642)
							(end 0.2794 0.1778)
						)
						(arc
							(start 0.2794 -0.1778)
							(mid 0.249642 -0.249642)
							(end 0.1778 -0.2794)
						)
					)
					(width 0)
					(fill yes)
				)
			)
		)
		(pad "2" smd custom
			(at 0 0.4445)
			(size 0.1397 0.1397)
			(layers "F.Cu" "F.Mask" "F.Paste")
			(net "GND")
			(options
				(clearance outline)
				(anchor circle)
			)
			(primitives
				(gr_poly
					(pts
						(arc
							(start -0.1778 -0.2794)
							(mid -0.249642 -0.249642)
							(end -0.2794 -0.1778)
						)
						(arc
							(start -0.2794 0.1778)
							(mid -0.249642 0.249642)
							(end -0.1778 0.2794)
						)
						(arc
							(start 0.1778 0.2794)
							(mid 0.249642 0.249642)
							(end 0.2794 0.1778)
						)
						(arc
							(start 0.2794 -0.1778)
							(mid 0.249642 -0.249642)
							(end 0.1778 -0.2794)
						)
					)
					(width 0)
					(fill yes)
				)
			)
		)
	)
	(footprint ""
		(layer "F.Cu")
		(at 97.155 -224.282)
		(property "Reference" "R9603"
			(at 0 0 0)
			(layer "F.SilkS")
			(hide yes)
			(effects
				(font
					(size 1.27 1.27)
				)
			)
		)
		(property "Value" "10R2F-L-GP"
			(at 0.064008 -3.993896 0)
			(unlocked yes)
			(layer "F.Fab")
			(hide yes)
			(effects
				(font
					(size 1.016 1.016)
					(thickness 0.1524)
				)
			)
		)
		(property "Device Type" "R402H14"
			(at 0.064008 -5.517896 0)
			(unlocked yes)
			(layer "F.Fab")
			(hide yes)
			(effects
				(font
					(size 1.016 1.016)
					(thickness 0.1524)
				)
			)
		)
		(duplicate_pad_numbers_are_jumpers no)
		(fp_line
			(start -0.508 -0.9398)
			(end -0.508 0.9398)
			(stroke
				(width 0.1524)
				(type default)
			)
			(layer "F.SilkS")
		)
		(fp_line
			(start 0.508 -0.9398)
			(end -0.508 -0.9398)
			(stroke
				(width 0.1524)
				(type default)
			)
			(layer "F.SilkS")
		)
		(fp_rect
			(start -0.508 0.9398)
			(end 0.508 -0.9398)
			(stroke
				(width 0)
				(type default)
			)
			(fill no)
			(layer "F.CrtYd")
		)
		(fp_rect
			(start -0.508 0.9398)
			(end 0.508 -0.9398)
			(stroke
				(width 0)
				(type default)
			)
			(fill no)
			(layer "F.Fab")
		)
		(pad "1" smd custom
			(at 0 -0.4445)
			(size 0.1397 0.1397)
			(layers "F.Cu" "F.Mask" "F.Paste")
			(net "SSD7_CLK0_OE_N")
			(options
				(clearance outline)
				(anchor circle)
			)
			(primitives
				(gr_poly
					(pts
						(arc
							(start -0.1778 -0.2794)
							(mid -0.249642 -0.249642)
							(end -0.2794 -0.1778)
						)
						(arc
							(start -0.2794 0.1778)
							(mid -0.249642 0.249642)
							(end -0.1778 0.2794)
						)
						(arc
							(start 0.1778 0.2794)
							(mid 0.249642 0.249642)
							(end 0.2794 0.1778)
						)
						(arc
							(start 0.2794 -0.1778)
							(mid 0.249642 -0.249642)
							(end 0.1778 -0.2794)
						)
					)
					(width 0)
					(fill yes)
				)
			)
		)
		(pad "2" smd custom
			(at 0 0.4445)
			(size 0.1397 0.1397)
			(layers "F.Cu" "F.Mask" "F.Paste")
			(net "SSD7_CLK0_OE_R_N")
			(options
				(clearance outline)
				(anchor circle)
			)
			(primitives
				(gr_poly
					(pts
						(arc
							(start -0.1778 -0.2794)
							(mid -0.249642 -0.249642)
							(end -0.2794 -0.1778)
						)
						(arc
							(start -0.2794 0.1778)
							(mid -0.249642 0.249642)
							(end -0.1778 0.2794)
						)
						(arc
							(start 0.1778 0.2794)
							(mid 0.249642 0.249642)
							(end 0.2794 0.1778)
						)
						(arc
							(start 0.2794 -0.1778)
							(mid 0.249642 -0.249642)
							(end 0.1778 -0.2794)
						)
					)
					(width 0)
					(fill yes)
				)
			)
		)
	)
	(footprint ""
		(layer "F.Cu")
		(at 27.5844 -414.274)
		(property "Reference" "PC1182"
			(at 0 0 0)
			(layer "F.SilkS")
			(hide yes)
			(effects
				(font
					(size 1.27 1.27)
				)
			)
		)
		(property "Value" "SCD1U50V3KX-GP"
			(at 0 -2.8194 0)
			(unlocked yes)
			(layer "F.Fab")
			(hide yes)
			(effects
				(font
					(size 1.016 1.016)
					(thickness 0.1524)
				)
			)
		)
		(property "Device Type" "C603H36"
			(at 0 -4.3434 0)
			(unlocked yes)
			(layer "F.Fab")
			(hide yes)
			(effects
				(font
					(size 1.016 1.016)
					(thickness 0.1524)
				)
			)
		)
		(duplicate_pad_numbers_are_jumpers no)
		(fp_line
			(start 0.508 0)
			(end -0.508 0)
			(stroke
				(width 0.2032)
				(type default)
			)
			(layer "F.SilkS")
		)
		(fp_rect
			(start -0.5842 1.3335)
			(end 0.5842 -1.3335)
			(stroke
				(width 0)
				(type default)
			)
			(fill no)
			(layer "F.CrtYd")
		)
		(fp_rect
			(start -0.5842 1.3335)
			(end 0.5842 -1.3335)
			(stroke
				(width 0)
				(type default)
			)
			(fill no)
			(layer "F.Fab")
		)
		(pad "1" smd custom
			(at 0 -0.762)
			(size 0.2159 0.2159)
			(layers "F.Cu" "F.Mask" "F.Paste")
			(net "P12V_SSD10")
			(options
				(clearance outline)
				(anchor circle)
			)
			(primitives
				(gr_poly
					(pts
						(arc
							(start -0.3302 -0.4318)
							(mid -0.402042 -0.402042)
							(end -0.4318 -0.3302)
						)
						(arc
							(start -0.4318 0.3302)
							(mid -0.402042 0.402042)
							(end -0.3302 0.4318)
						)
						(arc
							(start 0.3302 0.4318)
							(mid 0.402042 0.402042)
							(end 0.4318 0.3302)
						)
						(arc
							(start 0.4318 -0.3302)
							(mid 0.402042 -0.402042)
							(end 0.3302 -0.4318)
						)
					)
					(width 0)
					(fill yes)
				)
			)
		)
		(pad "2" smd custom
			(at 0 0.762)
			(size 0.2159 0.2159)
			(layers "F.Cu" "F.Mask" "F.Paste")
			(net "GND")
			(options
				(clearance outline)
				(anchor circle)
			)
			(primitives
				(gr_poly
					(pts
						(arc
							(start -0.3302 -0.4318)
							(mid -0.402042 -0.402042)
							(end -0.4318 -0.3302)
						)
						(arc
							(start -0.4318 0.3302)
							(mid -0.402042 0.402042)
							(end -0.3302 0.4318)
						)
						(arc
							(start 0.3302 0.4318)
							(mid 0.402042 0.402042)
							(end 0.4318 0.3302)
						)
						(arc
							(start 0.4318 -0.3302)
							(mid 0.402042 -0.402042)
							(end 0.3302 -0.4318)
						)
					)
					(width 0)
					(fill yes)
				)
			)
		)
	)
	(footprint ""
		(layer "F.Cu")
		(at 202.752706 -498.959378 -90)
		(property "Reference" "Q24"
			(at 0 0 270)
			(layer "F.SilkS")
			(hide yes)
			(effects
				(font
					(size 1.27 1.27)
				)
			)
		)
		(property "Value" "2N7002A-7-GP"
			(at 0.127 -8.9662 270)
			(unlocked yes)
			(layer "F.Fab")
			(hide yes)
			(effects
				(font
					(size 1.016 1.016)
					(thickness 0.1524)
				)
			)
		)
		(property "Device Type" "SOT23DGS2D4H48"
			(at 0.127 -10.4902 270)
			(unlocked yes)
			(layer "F.Fab")
			(hide yes)
			(effects
				(font
					(size 1.016 1.016)
					(thickness 0.1524)
				)
			)
		)
		(duplicate_pad_numbers_are_jumpers no)
		(fp_line
			(start -1.651 1.778)
			(end 1.651 1.778)
			(stroke
				(width 0.1524)
				(type default)
			)
			(layer "F.SilkS")
		)
		(fp_line
			(start 1.651 1.778)
			(end 1.651 -1.778)
			(stroke
				(width 0.1524)
				(type default)
			)
			(layer "F.SilkS")
		)
		(fp_line
			(start -1.651 -1.778)
			(end -1.651 1.778)
			(stroke
				(width 0.1524)
				(type default)
			)
			(layer "F.SilkS")
		)
		(fp_line
			(start 1.651 -1.778)
			(end -1.651 -1.778)
			(stroke
				(width 0.1524)
				(type default)
			)
			(layer "F.SilkS")
		)
		(fp_poly
			(pts
				(xy -1.778 1.8796) (xy -1.778 -1.8796) (xy 1.778 -1.8796) (xy 1.778 1.8796)
			)
			(stroke
				(width 0)
				(type default)
			)
			(fill no)
			(layer "F.CrtYd")
		)
		(fp_poly
			(pts
				(xy -1.778 1.8796) (xy -1.778 -1.8796) (xy 1.778 -1.8796) (xy 1.778 1.8796)
			)
			(stroke
				(width 0)
				(type default)
			)
			(fill no)
			(layer "F.Fab")
		)
		(pad "D" smd custom
			(at 0 -0.9525 270)
			(size 0.1905 0.1905)
			(layers "F.Cu" "F.Mask" "F.Paste")
			(net "P12V_MOST0_GATE_D")
			(options
				(clearance outline)
				(anchor circle)
			)
			(primitives
				(gr_poly
					(pts
						(arc
							(start -0.1778 0.5715)
							(mid -0.321484 0.511984)
							(end -0.381 0.3683)
						)
						(arc
							(start -0.381 -0.3683)
							(mid -0.321484 -0.511984)
							(end -0.1778 -0.5715)
						)
						(arc
							(start 0.1778 -0.5715)
							(mid 0.321484 -0.511984)
							(end 0.381 -0.3683)
						)
						(arc
							(start 0.381 0.3683)
							(mid 0.321484 0.511984)
							(end 0.1778 0.5715)
						)
					)
					(width 0)
					(fill yes)
				)
			)
		)
		(pad "G" smd custom
			(at -0.98425 0.9525 270)
			(size 0.1905 0.1905)
			(layers "F.Cu" "F.Mask" "F.Paste")
			(net "P12V_MOST0_GATE")
			(options
				(clearance outline)
				(anchor circle)
			)
			(primitives
				(gr_poly
					(pts
						(arc
							(start -0.1778 0.5715)
							(mid -0.321484 0.511984)
							(end -0.381 0.3683)
						)
						(arc
							(start -0.381 -0.3683)
							(mid -0.321484 -0.511984)
							(end -0.1778 -0.5715)
						)
						(arc
							(start 0.1778 -0.5715)
							(mid 0.321484 -0.511984)
							(end 0.381 -0.3683)
						)
						(arc
							(start 0.381 0.3683)
							(mid 0.321484 0.511984)
							(end 0.1778 0.5715)
						)
					)
					(width 0)
					(fill yes)
				)
			)
		)
		(pad "S" smd custom
			(at 0.98425 0.9525 270)
			(size 0.1905 0.1905)
			(layers "F.Cu" "F.Mask" "F.Paste")
			(net "GND")
			(options
				(clearance outline)
				(anchor circle)
			)
			(primitives
				(gr_poly
					(pts
						(arc
							(start -0.1778 0.5715)
							(mid -0.321484 0.511984)
							(end -0.381 0.3683)
						)
						(arc
							(start -0.381 -0.3683)
							(mid -0.321484 -0.511984)
							(end -0.1778 -0.5715)
						)
						(arc
							(start 0.1778 -0.5715)
							(mid 0.321484 -0.511984)
							(end 0.381 -0.3683)
						)
						(arc
							(start 0.381 0.3683)
							(mid 0.321484 0.511984)
							(end 0.1778 0.5715)
						)
					)
					(width 0)
					(fill yes)
				)
			)
		)
	)
	(footprint ""
		(layer "F.Cu")
		(at 209.296 -297.18 180)
		(property "Reference" "Q10"
			(at 0 0 180)
			(layer "F.SilkS")
			(hide yes)
			(effects
				(font
					(size 1.27 1.27)
				)
			)
		)
		(property "Value" "2N7002A-7-GP"
			(at 0.127 -8.9662 180)
			(unlocked yes)
			(layer "F.Fab")
			(hide yes)
			(effects
				(font
					(size 1.016 1.016)
					(thickness 0.1524)
				)
			)
		)
		(property "Device Type" "SOT23DGS2D4H48"
			(at 0.127 -10.4902 180)
			(unlocked yes)
			(layer "F.Fab")
			(hide yes)
			(effects
				(font
					(size 1.016 1.016)
					(thickness 0.1524)
				)
			)
		)
		(duplicate_pad_numbers_are_jumpers no)
		(fp_line
			(start 1.651 1.778)
			(end 1.651 -1.778)
			(stroke
				(width 0.1524)
				(type default)
			)
			(layer "F.SilkS")
		)
		(fp_line
			(start 1.651 -1.778)
			(end -1.651 -1.778)
			(stroke
				(width 0.1524)
				(type default)
			)
			(layer "F.SilkS")
		)
		(fp_line
			(start -1.651 1.778)
			(end 1.651 1.778)
			(stroke
				(width 0.1524)
				(type default)
			)
			(layer "F.SilkS")
		)
		(fp_line
			(start -1.651 -1.778)
			(end -1.651 1.778)
			(stroke
				(width 0.1524)
				(type default)
			)
			(layer "F.SilkS")
		)
		(fp_poly
			(pts
				(xy -1.778 1.8796) (xy -1.778 -1.8796) (xy 1.778 -1.8796) (xy 1.778 1.8796)
			)
			(stroke
				(width 0)
				(type default)
			)
			(fill no)
			(layer "F.CrtYd")
		)
		(fp_poly
			(pts
				(xy -1.778 1.8796) (xy -1.778 -1.8796) (xy 1.778 -1.8796) (xy 1.778 1.8796)
			)
			(stroke
				(width 0)
				(type default)
			)
			(fill no)
			(layer "F.Fab")
		)
		(pad "D" smd custom
			(at 0 -0.9525 180)
			(size 0.1905 0.1905)
			(layers "F.Cu" "F.Mask" "F.Paste")
			(net "SW_SSD2_R")
			(options
				(clearance outline)
				(anchor circle)
			)
			(primitives
				(gr_poly
					(pts
						(arc
							(start -0.1778 0.5715)
							(mid -0.321484 0.511984)
							(end -0.381 0.3683)
						)
						(arc
							(start -0.381 -0.3683)
							(mid -0.321484 -0.511984)
							(end -0.1778 -0.5715)
						)
						(arc
							(start 0.1778 -0.5715)
							(mid 0.321484 -0.511984)
							(end 0.381 -0.3683)
						)
						(arc
							(start 0.381 0.3683)
							(mid 0.321484 0.511984)
							(end 0.1778 0.5715)
						)
					)
					(width 0)
					(fill yes)
				)
			)
		)
		(pad "G" smd custom
			(at -0.98425 0.9525 180)
			(size 0.1905 0.1905)
			(layers "F.Cu" "F.Mask" "F.Paste")
			(net "SSD2_PWREN")
			(options
				(clearance outline)
				(anchor circle)
			)
			(primitives
				(gr_poly
					(pts
						(arc
							(start -0.1778 0.5715)
							(mid -0.321484 0.511984)
							(end -0.381 0.3683)
						)
						(arc
							(start -0.381 -0.3683)
							(mid -0.321484 -0.511984)
							(end -0.1778 -0.5715)
						)
						(arc
							(start 0.1778 -0.5715)
							(mid 0.321484 -0.511984)
							(end 0.381 -0.3683)
						)
						(arc
							(start 0.381 0.3683)
							(mid 0.321484 0.511984)
							(end 0.1778 0.5715)
						)
					)
					(width 0)
					(fill yes)
				)
			)
		)
		(pad "S" smd custom
			(at 0.98425 0.9525 180)
			(size 0.1905 0.1905)
			(layers "F.Cu" "F.Mask" "F.Paste")
			(net "GND")
			(options
				(clearance outline)
				(anchor circle)
			)
			(primitives
				(gr_poly
					(pts
						(arc
							(start -0.1778 0.5715)
							(mid -0.321484 0.511984)
							(end -0.381 0.3683)
						)
						(arc
							(start -0.381 -0.3683)
							(mid -0.321484 -0.511984)
							(end -0.1778 -0.5715)
						)
						(arc
							(start 0.1778 -0.5715)
							(mid 0.321484 -0.511984)
							(end 0.381 -0.3683)
						)
						(arc
							(start 0.381 0.3683)
							(mid 0.321484 0.511984)
							(end 0.1778 0.5715)
						)
					)
					(width 0)
					(fill yes)
				)
			)
		)
	)
	(footprint ""
		(layer "F.Cu")
		(at 72.3646 -352.679 180)
		(property "Reference" "R375"
			(at 0 0 180)
			(layer "F.SilkS")
			(hide yes)
			(effects
				(font
					(size 1.27 1.27)
				)
			)
		)
		(property "Value" "4K7R2J-2-GP"
			(at 0.064008 -3.993896 180)
			(unlocked yes)
			(layer "F.Fab")
			(hide yes)
			(effects
				(font
					(size 1.016 1.016)
					(thickness 0.1524)
				)
			)
		)
		(property "Device Type" "R402H16"
			(at 0.064008 -5.517896 180)
			(unlocked yes)
			(layer "F.Fab")
			(hide yes)
			(effects
				(font
					(size 1.016 1.016)
					(thickness 0.1524)
				)
			)
		)
		(duplicate_pad_numbers_are_jumpers no)
		(fp_line
			(start 0.508 -0.9398)
			(end -0.508 -0.9398)
			(stroke
				(width 0.1524)
				(type default)
			)
			(layer "F.SilkS")
		)
		(fp_line
			(start -0.508 -0.9398)
			(end -0.508 0.9398)
			(stroke
				(width 0.1524)
				(type default)
			)
			(layer "F.SilkS")
		)
		(fp_rect
			(start -0.508 0.9398)
			(end 0.508 -0.9398)
			(stroke
				(width 0)
				(type default)
			)
			(fill no)
			(layer "F.CrtYd")
		)
		(fp_rect
			(start -0.508 0.9398)
			(end 0.508 -0.9398)
			(stroke
				(width 0)
				(type default)
			)
			(fill no)
			(layer "F.Fab")
		)
		(pad "1" smd custom
			(at 0 -0.4445 180)
			(size 0.1397 0.1397)
			(layers "F.Cu" "F.Mask" "F.Paste")
			(net "P3V3")
			(options
				(clearance outline)
				(anchor circle)
			)
			(primitives
				(gr_poly
					(pts
						(arc
							(start -0.1778 -0.2794)
							(mid -0.249642 -0.249642)
							(end -0.2794 -0.1778)
						)
						(arc
							(start -0.2794 0.1778)
							(mid -0.249642 0.249642)
							(end -0.1778 0.2794)
						)
						(arc
							(start 0.1778 0.2794)
							(mid 0.249642 0.249642)
							(end 0.2794 0.1778)
						)
						(arc
							(start 0.2794 -0.1778)
							(mid 0.249642 -0.249642)
							(end 0.1778 -0.2794)
						)
					)
					(width 0)
					(fill yes)
				)
			)
		)
		(pad "2" smd custom
			(at 0 0.4445 180)
			(size 0.1397 0.1397)
			(layers "F.Cu" "F.Mask" "F.Paste")
			(net "BMC_I2C_SCL_BUF_9")
			(options
				(clearance outline)
				(anchor circle)
			)
			(primitives
				(gr_poly
					(pts
						(arc
							(start -0.1778 -0.2794)
							(mid -0.249642 -0.249642)
							(end -0.2794 -0.1778)
						)
						(arc
							(start -0.2794 0.1778)
							(mid -0.249642 0.249642)
							(end -0.1778 0.2794)
						)
						(arc
							(start 0.1778 0.2794)
							(mid 0.249642 0.249642)
							(end 0.2794 0.1778)
						)
						(arc
							(start 0.2794 -0.1778)
							(mid 0.249642 -0.249642)
							(end 0.1778 -0.2794)
						)
					)
					(width 0)
					(fill yes)
				)
			)
		)
	)
)
